(kicad_pcb
	(version 20260206)
	(generator "pcbnew")
	(generator_version "10.0")
	(general
		(thickness 1.6)
		(legacy_teardrops no)
	)
	(paper "A4")
	(title_block
		(title "01162023_DA0F0TEBIF0_F0T_Expander_BD_F_brd_V02_OCP.brd")
		(comment 1 "Grand Teton / footprints 1419-1425 of 9728")
	)
	(layers
		(0 "F.Cu" signal "TOP")
		(4 "In1.Cu" signal "GND")
		(6 "In2.Cu" signal "VCC")
		(8 "In3.Cu" signal "VCC1")
		(10 "In4.Cu" signal "GND1")
		(12 "In5.Cu" signal "IN1")
		(14 "In6.Cu" signal "GND2")
		(16 "In7.Cu" signal "IN2")
		(18 "In8.Cu" signal "GND3")
		(20 "In9.Cu" signal "IN3")
		(22 "In10.Cu" signal "GND4")
		(24 "In11.Cu" signal "IN4")
		(26 "In12.Cu" signal "GND5")
		(28 "In13.Cu" signal "IN5")
		(30 "In14.Cu" signal "GND6")
		(32 "In15.Cu" signal "IN6")
		(34 "In16.Cu" signal "GND7")
		(2 "B.Cu" signal "BOTTOM")
		(9 "F.Adhes" user "F.Adhesive")
		(11 "B.Adhes" user "B.Adhesive")
		(13 "F.Paste" user "Package Geometry/Pastemask Top")
		(15 "B.Paste" user "Package Geometry/Pastemask Bottom")
		(5 "F.SilkS" user "Ref Des/Silkscreen Top")
		(7 "B.SilkS" user "Ref Des/Silkscreen Bottom")
		(1 "F.Mask" user "Board Geometry/Soldermask Top")
		(3 "B.Mask" user "Board Geometry/Soldermask Bottom")
		(17 "Dwgs.User" user "User.Drawings")
		(19 "Cmts.User" user "User.Comments")
		(21 "Eco1.User" user "User.Eco1")
		(23 "Eco2.User" user "User.Eco2")
		(25 "Edge.Cuts" user "Board Geometry/Outline")
		(27 "Margin" user)
		(31 "F.CrtYd" user "Package Geometry/Place Bound Top")
		(29 "B.CrtYd" user "Package Geometry/Place Bound Bottom")
		(35 "F.Fab" user "Ref Des/Assembly Top")
		(33 "B.Fab" user "Ref Des/Assembly Bottom")
	)
	(footprint ""
		(layer "F.Cu")
		(at 465.746846 -522.606778 180)
		(property "Reference" "SCREW_SSD7_1"
			(at -5.207 -1.402334 0)
			(unlocked yes)
			(layer "B.SilkS")
			(effects
				(font
					(size 0.7874 0.5842)
					(thickness 0.1524)
				)
				(justify mirror)
			)
		)
		(property "Value" ""
			(at 0 0 180)
			(layer "F.Fab")
			(effects
				(font
					(size 1.27 1.27)
				)
			)
		)
		(duplicate_pad_numbers_are_jumpers no)
		(pad "1" thru_hole circle
			(at 0 0 180)
			(size 0.4572 0.4572)
			(drill 0.2032)
			(layers "*.Cu" "*.Mask")
			(remove_unused_layers no)
			(net "Net_9130")
			(clearance 0.127)
			(thermal_gap 0.127)
			(padstack
				(mode front_inner_back)
				(layer "Inner"
					(shape circle)
					(size 0.4572 0.4572)
					(clearance 0.127)
				)
				(layer "B.Cu"
					(shape circle)
					(size 0.508 0.508)
					(clearance 0.1016)
				)
			)
		)
	)
	(footprint ""
		(layer "F.Cu")
		(at 158.088076 -45.704252 90)
		(property "Reference" "R562"
			(at 0 0 90)
			(layer "F.SilkS")
			(hide yes)
			(effects
				(font
					(size 1.27 1.27)
				)
			)
		)
		(property "Value" ""
			(at 0 0 90)
			(layer "F.Fab")
			(effects
				(font
					(size 1.27 1.27)
				)
			)
		)
		(duplicate_pad_numbers_are_jumpers no)
		(fp_line
			(start 3.937508 -1.8796)
			(end -3.937508 -1.8796)
			(stroke
				(width 0.1524)
				(type default)
			)
			(layer "F.SilkS")
		)
		(fp_line
			(start -3.937508 -1.8796)
			(end -3.937508 1.8796)
			(stroke
				(width 0.1524)
				(type default)
			)
			(layer "F.SilkS")
		)
		(fp_line
			(start 3.937508 1.8796)
			(end 3.937508 -1.8796)
			(stroke
				(width 0.1524)
				(type default)
			)
			(layer "F.SilkS")
		)
		(fp_line
			(start -3.937508 1.8796)
			(end 3.937508 1.8796)
			(stroke
				(width 0.1524)
				(type default)
			)
			(layer "F.SilkS")
		)
		(fp_line
			(start 3.275076 -1.674876)
			(end -3.275076 -1.674876)
			(stroke
				(width 0.1)
				(type default)
			)
			(layer "F.Fab")
		)
		(fp_line
			(start -3.275076 -1.674876)
			(end -3.275076 1.674876)
			(stroke
				(width 0.1)
				(type default)
			)
			(layer "F.Fab")
		)
		(fp_line
			(start 3.275076 1.674876)
			(end 3.275076 -1.674876)
			(stroke
				(width 0.1)
				(type default)
			)
			(layer "F.Fab")
		)
		(fp_line
			(start -3.275076 1.674876)
			(end 3.275076 1.674876)
			(stroke
				(width 0.1)
				(type default)
			)
			(layer "F.Fab")
		)
		(pad "1" smd rect
			(at -2.350008 0 90)
			(size 2.921 3.5052)
			(layers "F.Cu" "F.Mask" "F.Paste")
			(net "P12V_SSD5")
		)
		(pad "2" smd rect
			(at 2.350008 0 90)
			(size 2.921 3.5052)
			(layers "F.Cu" "F.Mask" "F.Paste")
			(net "P12V_SSD5_R")
		)
	)
	(footprint ""
		(layer "F.Cu")
		(at 80.124554 -84.476336 180)
		(property "Reference" "U16"
			(at -2.782316 -0.402336 90)
			(unlocked yes)
			(layer "F.SilkS")
			(effects
				(font
					(size 0.7874 0.5842)
					(thickness 0.1524)
				)
				(justify left)
			)
		)
		(property "Value" ""
			(at 0 0 180)
			(layer "F.Fab")
			(effects
				(font
					(size 1.27 1.27)
				)
			)
		)
		(duplicate_pad_numbers_are_jumpers no)
		(fp_line
			(start 2.0574 1.651)
			(end -2.0574 1.651)
			(stroke
				(width 0.1524)
				(type default)
			)
			(layer "F.SilkS")
		)
		(fp_line
			(start 2.0574 -1.651)
			(end 2.0574 1.651)
			(stroke
				(width 0.1524)
				(type default)
			)
			(layer "F.SilkS")
		)
		(fp_line
			(start 0.381 -1.651)
			(end 2.0574 -1.651)
			(stroke
				(width 0.1524)
				(type default)
			)
			(layer "F.SilkS")
		)
		(fp_line
			(start 0 -1.016)
			(end 0.381 -1.651)
			(stroke
				(width 0.1524)
				(type default)
			)
			(layer "F.SilkS")
		)
		(fp_line
			(start -0.381 -1.651)
			(end 0 -1.016)
			(stroke
				(width 0.1524)
				(type default)
			)
			(layer "F.SilkS")
		)
		(fp_line
			(start -2.0574 1.651)
			(end -2.0574 -1.651)
			(stroke
				(width 0.1524)
				(type default)
			)
			(layer "F.SilkS")
		)
		(fp_line
			(start -2.0574 -1.651)
			(end -0.381 -1.651)
			(stroke
				(width 0.1524)
				(type default)
			)
			(layer "F.SilkS")
		)
		(fp_poly
			(pts
				(xy -2.71272 -0.719328) (xy -2.71272 -1.344168) (xy -2.159 -1.016)
			)
			(stroke
				(width 0)
				(type default)
			)
			(fill yes)
			(layer "F.SilkS")
		)
		(fp_line
			(start 1.599946 1.199896)
			(end 0.899922 1.199896)
			(stroke
				(width 0.1)
				(type default)
			)
			(layer "F.Fab")
		)
		(fp_line
			(start 1.599946 -1.199896)
			(end 1.599946 1.199896)
			(stroke
				(width 0.1)
				(type default)
			)
			(layer "F.Fab")
		)
		(fp_line
			(start 0.899922 1.549908)
			(end -0.899922 1.549908)
			(stroke
				(width 0.1)
				(type default)
			)
			(layer "F.Fab")
		)
		(fp_line
			(start 0.899922 1.199896)
			(end 0.899922 1.549908)
			(stroke
				(width 0.1)
				(type default)
			)
			(layer "F.Fab")
		)
		(fp_line
			(start 0.899922 -1.199896)
			(end 1.599946 -1.199896)
			(stroke
				(width 0.1)
				(type default)
			)
			(layer "F.Fab")
		)
		(fp_line
			(start 0.899922 -1.549908)
			(end 0.899922 -1.199896)
			(stroke
				(width 0.1)
				(type default)
			)
			(layer "F.Fab")
		)
		(fp_line
			(start -0.899922 1.549908)
			(end -0.899922 1.199896)
			(stroke
				(width 0.1)
				(type default)
			)
			(layer "F.Fab")
		)
		(fp_line
			(start -0.899922 1.199896)
			(end -1.599946 1.199896)
			(stroke
				(width 0.1)
				(type default)
			)
			(layer "F.Fab")
		)
		(fp_line
			(start -0.899922 -1.199896)
			(end -0.899922 -1.549908)
			(stroke
				(width 0.1)
				(type default)
			)
			(layer "F.Fab")
		)
		(fp_line
			(start -0.899922 -1.549908)
			(end 0.899922 -1.549908)
			(stroke
				(width 0.1)
				(type default)
			)
			(layer "F.Fab")
		)
		(fp_line
			(start -1.599946 1.199896)
			(end -1.599946 -1.199896)
			(stroke
				(width 0.1)
				(type default)
			)
			(layer "F.Fab")
		)
		(fp_line
			(start -1.599946 -1.199896)
			(end -0.899922 -1.199896)
			(stroke
				(width 0.1)
				(type default)
			)
			(layer "F.Fab")
		)
		(fp_poly
			(pts
				(xy -2.71272 -0.719328) (xy -2.71272 -1.344168) (xy -2.159 -1.016)
			)
			(stroke
				(width 0)
				(type default)
			)
			(fill yes)
			(layer "F.Fab")
		)
		(pad "1" smd rect
			(at -1.225042 -0.94996 90)
			(size 0.5588 1.3462)
			(layers "F.Cu" "F.Mask" "F.Paste")
			(net "HP_NIC1_PWRGD_R")
		)
		(pad "2" smd rect
			(at -1.225042 0 90)
			(size 0.5588 1.3462)
			(layers "F.Cu" "F.Mask" "F.Paste")
			(net "RST_NIC1_PERST_R_N")
		)
		(pad "3" smd rect
			(at -1.225042 0.94996 90)
			(size 0.5588 1.3462)
			(layers "F.Cu" "F.Mask" "F.Paste")
			(net "GND")
		)
		(pad "4" smd rect
			(at 1.225042 0.94996 90)
			(size 0.5588 1.3462)
			(layers "F.Cu" "F.Mask" "F.Paste")
			(net "RST_HP_NIC1_N")
		)
		(pad "5" smd rect
			(at 1.225042 -0.94996 90)
			(size 0.5588 1.3462)
			(layers "F.Cu" "F.Mask" "F.Paste")
			(net "P3V3_AUX")
		)
	)
	(footprint ""
		(layer "F.Cu")
		(at 280.307542 -343.952322 90)
		(property "Reference" "C2351"
			(at 0 0 90)
			(layer "F.SilkS")
			(hide yes)
			(effects
				(font
					(size 1.27 1.27)
				)
			)
		)
		(property "Value" ""
			(at 0 0 90)
			(layer "F.Fab")
			(effects
				(font
					(size 1.27 1.27)
				)
			)
		)
		(duplicate_pad_numbers_are_jumpers no)
		(fp_line
			(start 0.299974 -0.150114)
			(end 0.299974 0.150114)
			(stroke
				(width 0.1)
				(type default)
			)
			(layer "F.Fab")
		)
		(fp_line
			(start -0.299974 -0.150114)
			(end 0.299974 -0.150114)
			(stroke
				(width 0.1)
				(type default)
			)
			(layer "F.Fab")
		)
		(fp_line
			(start 0.299974 0.150114)
			(end -0.299974 0.150114)
			(stroke
				(width 0.1)
				(type default)
			)
			(layer "F.Fab")
		)
		(fp_line
			(start -0.299974 0.150114)
			(end -0.299974 -0.150114)
			(stroke
				(width 0.1)
				(type default)
			)
			(layer "F.Fab")
		)
		(pad "1" smd rect
			(at -0.2667 0 90)
			(size 0.3048 0.381)
			(layers "F.Cu" "F.Mask" "F.Paste")
			(net "P5E_PEX2_STN4_TX_DP<74>")
		)
		(pad "2" smd rect
			(at 0.2667 0 90)
			(size 0.3048 0.381)
			(layers "F.Cu" "F.Mask" "F.Paste")
			(net "P5E_PEX2_STN4_TX_C_DP<74>")
		)
	)
	(footprint ""
		(layer "F.Cu")
		(at 154.666442 -252.356874 -90)
		(property "Reference" "R1288"
			(at 0 0 270)
			(layer "F.SilkS")
			(hide yes)
			(effects
				(font
					(size 1.27 1.27)
				)
			)
		)
		(property "Value" ""
			(at 0 0 270)
			(layer "F.Fab")
			(effects
				(font
					(size 1.27 1.27)
				)
			)
		)
		(duplicate_pad_numbers_are_jumpers no)
		(fp_line
			(start -0.7874 0.4064)
			(end -0.7874 -0.4064)
			(stroke
				(width 0.1524)
				(type default)
			)
			(layer "F.SilkS")
		)
		(fp_line
			(start 0.7874 0.4064)
			(end -0.7874 0.4064)
			(stroke
				(width 0.1524)
				(type default)
			)
			(layer "F.SilkS")
		)
		(fp_line
			(start -0.7874 -0.4064)
			(end 0.7874 -0.4064)
			(stroke
				(width 0.1524)
				(type default)
			)
			(layer "F.SilkS")
		)
		(fp_line
			(start 0.7874 -0.4064)
			(end 0.7874 0.4064)
			(stroke
				(width 0.1524)
				(type default)
			)
			(layer "F.SilkS")
		)
		(fp_line
			(start -0.67945 0.3048)
			(end -0.67945 -0.305054)
			(stroke
				(width 0.1)
				(type default)
			)
			(layer "F.Fab")
		)
		(fp_line
			(start -0.12065 0.3048)
			(end -0.67945 0.3048)
			(stroke
				(width 0.1)
				(type default)
			)
			(layer "F.Fab")
		)
		(fp_line
			(start 0.120396 0.3048)
			(end 0.120396 0.2794)
			(stroke
				(width 0.1)
				(type default)
			)
			(layer "F.Fab")
		)
		(fp_line
			(start 0.67945 0.3048)
			(end 0.120396 0.3048)
			(stroke
				(width 0.1)
				(type default)
			)
			(layer "F.Fab")
		)
		(fp_line
			(start -0.12065 0.2794)
			(end -0.12065 0.3048)
			(stroke
				(width 0.1)
				(type default)
			)
			(layer "F.Fab")
		)
		(fp_line
			(start 0.120396 0.2794)
			(end -0.12065 0.2794)
			(stroke
				(width 0.1)
				(type default)
			)
			(layer "F.Fab")
		)
		(fp_line
			(start -0.12065 -0.2794)
			(end 0.12065 -0.2794)
			(stroke
				(width 0.1)
				(type default)
			)
			(layer "F.Fab")
		)
		(fp_line
			(start 0.12065 -0.2794)
			(end 0.12065 -0.3048)
			(stroke
				(width 0.1)
				(type default)
			)
			(layer "F.Fab")
		)
		(fp_line
			(start 0.12065 -0.3048)
			(end 0.67945 -0.3048)
			(stroke
				(width 0.1)
				(type default)
			)
			(layer "F.Fab")
		)
		(fp_line
			(start 0.67945 -0.3048)
			(end 0.67945 0.3048)
			(stroke
				(width 0.1)
				(type default)
			)
			(layer "F.Fab")
		)
		(fp_line
			(start -0.67945 -0.305054)
			(end -0.12065 -0.305054)
			(stroke
				(width 0.1)
				(type default)
			)
			(layer "F.Fab")
		)
		(fp_line
			(start -0.12065 -0.305054)
			(end -0.12065 -0.2794)
			(stroke
				(width 0.1)
				(type default)
			)
			(layer "F.Fab")
		)
		(pad "1" smd circle
			(at -0.40005 0 270)
			(size 0 0)
			(layers "F.Cu" "F.Mask" "F.Paste")
			(net "GND")
		)
		(pad "2" smd circle
			(at 0.40005 0 270)
			(size 0 0)
			(layers "F.Cu" "F.Mask" "F.Paste")
			(net "PEX1_DBG_MODE4")
		)
	)
	(footprint ""
		(layer "F.Cu")
		(at 318.695324 -356.244906 90)
		(property "Reference" "C557"
			(at 0 0 90)
			(layer "F.SilkS")
			(hide yes)
			(effects
				(font
					(size 1.27 1.27)
				)
			)
		)
		(property "Value" ""
			(at 0 0 90)
			(layer "F.Fab")
			(effects
				(font
					(size 1.27 1.27)
				)
			)
		)
		(duplicate_pad_numbers_are_jumpers no)
		(fp_line
			(start 0.299974 -0.150114)
			(end 0.299974 0.150114)
			(stroke
				(width 0.1)
				(type default)
			)
			(layer "F.Fab")
		)
		(fp_line
			(start -0.299974 -0.150114)
			(end 0.299974 -0.150114)
			(stroke
				(width 0.1)
				(type default)
			)
			(layer "F.Fab")
		)
		(fp_line
			(start 0.299974 0.150114)
			(end -0.299974 0.150114)
			(stroke
				(width 0.1)
				(type default)
			)
			(layer "F.Fab")
		)
		(fp_line
			(start -0.299974 0.150114)
			(end -0.299974 -0.150114)
			(stroke
				(width 0.1)
				(type default)
			)
			(layer "F.Fab")
		)
		(pad "1" smd rect
			(at -0.2667 0 90)
			(size 0.3048 0.381)
			(layers "F.Cu" "F.Mask" "F.Paste")
			(net "P5E_PEX2_STN6_TX_DP<108>")
		)
		(pad "2" smd rect
			(at 0.2667 0 90)
			(size 0.3048 0.381)
			(layers "F.Cu" "F.Mask" "F.Paste")
			(net "P5E_PEX2_STN6_TX_C_DP<108>")
		)
	)
	(footprint ""
		(layer "F.Cu")
		(at 373.507 -199.009)
		(property "Reference" "U345"
			(at -1.3462 -4.613148 0)
			(unlocked yes)
			(layer "F.SilkS")
			(effects
				(font
					(size 0.7874 0.5842)
					(thickness 0.1524)
				)
				(justify left)
			)
		)
		(property "Value" ""
			(at 0 0 0)
			(layer "F.Fab")
			(effects
				(font
					(size 1.27 1.27)
				)
			)
		)
		(duplicate_pad_numbers_are_jumpers no)
		(fp_line
			(start -2.097532 -3.949954)
			(end -2.097532 3.949954)
			(stroke
				(width 0.1524)
				(type default)
			)
			(layer "F.SilkS")
		)
		(fp_line
			(start -2.097532 3.949954)
			(end 2.097532 3.949954)
			(stroke
				(width 0.1524)
				(type default)
			)
			(layer "F.SilkS")
		)
		(fp_line
			(start -1.409954 -3.949954)
			(end -2.097532 -3.949954)
			(stroke
				(width 0.1524)
				(type default)
			)
			(layer "F.SilkS")
		)
		(fp_line
			(start 0 -2.54)
			(end -1.409954 -3.949954)
			(stroke
				(width 0.1524)
				(type default)
			)
			(layer "F.SilkS")
		)
		(fp_line
			(start 1.409954 -3.949954)
			(end 0 -2.54)
			(stroke
				(width 0.1524)
				(type default)
			)
			(layer "F.SilkS")
		)
		(fp_line
			(start 2.097532 -3.949954)
			(end 1.409954 -3.949954)
			(stroke
				(width 0.1524)
				(type default)
			)
			(layer "F.SilkS")
		)
		(fp_line
			(start 2.097532 3.949954)
			(end 2.097532 -3.949954)
			(stroke
				(width 0.1524)
				(type default)
			)
			(layer "F.SilkS")
		)
		(fp_poly
			(pts
				(xy -4.7498 -4.182872) (xy -4.7498 -3.166872) (xy -3.7338 -3.674872)
			)
			(stroke
				(width 0)
				(type default)
			)
			(fill yes)
			(layer "F.SilkS")
		)
		(fp_line
			(start -2.249932 -3.949954)
			(end -2.249932 3.949954)
			(stroke
				(width 0.1)
				(type default)
			)
			(layer "F.Fab")
		)
		(fp_line
			(start -2.249932 3.949954)
			(end 2.249932 3.949954)
			(stroke
				(width 0.1)
				(type default)
			)
			(layer "F.Fab")
		)
		(fp_line
			(start 2.249932 -3.949954)
			(end -2.249932 -3.949954)
			(stroke
				(width 0.1)
				(type default)
			)
			(layer "F.Fab")
		)
		(fp_line
			(start 2.249932 3.949954)
			(end 2.249932 -3.949954)
			(stroke
				(width 0.1)
				(type default)
			)
			(layer "F.Fab")
		)
		(fp_poly
			(pts
				(xy -4.7498 -4.182872) (xy -4.7498 -3.166872) (xy -3.7338 -3.674872)
			)
			(stroke
				(width 0)
				(type default)
			)
			(fill yes)
			(layer "F.Fab")
		)
		(pad "1" smd rect
			(at -2.925064 -3.674872 270)
			(size 0.6096 1.3716)
			(layers "F.Cu" "F.Mask" "F.Paste")
			(net "PEX1_PCA9555_0_INT_N")
		)
		(pad "2" smd rect
			(at -2.925064 -2.925064 270)
			(size 0.4064 1.3716)
			(layers "F.Cu" "F.Mask" "F.Paste")
			(net "PCA9555_0_PEX1_A1")
		)
		(pad "3" smd rect
			(at -2.925064 -2.275078 270)
			(size 0.4064 1.3716)
			(layers "F.Cu" "F.Mask" "F.Paste")
			(net "PCA9555_0_PEX1_A2")
		)
		(pad "4" smd rect
			(at -2.925064 -1.625092 270)
			(size 0.4064 1.3716)
			(layers "F.Cu" "F.Mask" "F.Paste")
			(net "PRSNT_SSD4_FPGA_PCA9555_N")
		)
		(pad "5" smd rect
			(at -2.925064 -0.975106 270)
			(size 0.4064 1.3716)
			(layers "F.Cu" "F.Mask" "F.Paste")
			(net "SSD4_PEX_PWR_EN")
		)
		(pad "6" smd rect
			(at -2.925064 -0.32512 270)
			(size 0.4064 1.3716)
			(layers "F.Cu" "F.Mask" "F.Paste")
			(net "RST_PEX_SSD4_PERST_N")
		)
		(pad "7" smd rect
			(at -2.925064 0.32512 270)
			(size 0.4064 1.3716)
			(layers "F.Cu" "F.Mask" "F.Paste")
			(net "Net_1169")
		)
		(pad "8" smd rect
			(at -2.925064 0.975106 270)
			(size 0.4064 1.3716)
			(layers "F.Cu" "F.Mask" "F.Paste")
			(net "PRSNT_SSD5_FPGA_PCA9555_N")
		)
		(pad "9" smd rect
			(at -2.925064 1.625092 270)
			(size 0.4064 1.3716)
			(layers "F.Cu" "F.Mask" "F.Paste")
			(net "SSD5_PEX_PWR_EN")
		)
		(pad "10" smd rect
			(at -2.925064 2.275078 270)
			(size 0.4064 1.3716)
			(layers "F.Cu" "F.Mask" "F.Paste")
			(net "RST_PEX_SSD5_PERST_N")
		)
		(pad "11" smd rect
			(at -2.925064 2.925064 270)
			(size 0.4064 1.3716)
			(layers "F.Cu" "F.Mask" "F.Paste")
			(net "Net_1170")
		)
		(pad "12" smd rect
			(at -2.925064 3.674872 270)
			(size 0.6096 1.3716)
			(layers "F.Cu" "F.Mask" "F.Paste")
			(net "GND")
		)
		(pad "13" smd rect
			(at 2.925064 3.674872 270)
			(size 0.6096 1.3716)
			(layers "F.Cu" "F.Mask" "F.Paste")
			(net "PRSNT_NIC2_FPGA_PCA9555_N")
		)
		(pad "14" smd rect
			(at 2.925064 2.925064 270)
			(size 0.4064 1.3716)
			(layers "F.Cu" "F.Mask" "F.Paste")
			(net "NIC2_PEX_PWR_EN")
		)
		(pad "15" smd rect
			(at 2.925064 2.275078 270)
			(size 0.4064 1.3716)
			(layers "F.Cu" "F.Mask" "F.Paste")
			(net "RST_PEX_NIC2_PERST_N")
		)
		(pad "16" smd rect
			(at 2.925064 1.625092 270)
			(size 0.4064 1.3716)
			(layers "F.Cu" "F.Mask" "F.Paste")
			(net "Net_1171")
		)
		(pad "17" smd rect
			(at 2.925064 0.975106 270)
			(size 0.4064 1.3716)
			(layers "F.Cu" "F.Mask" "F.Paste")
			(net "Net_8984")
		)
		(pad "18" smd rect
			(at 2.925064 0.32512 270)
			(size 0.4064 1.3716)
			(layers "F.Cu" "F.Mask" "F.Paste")
			(net "Net_8983")
		)
		(pad "19" smd rect
			(at 2.925064 -0.32512 270)
			(size 0.4064 1.3716)
			(layers "F.Cu" "F.Mask" "F.Paste")
			(net "Net_8982")
		)
		(pad "20" smd rect
			(at 2.925064 -0.975106 270)
			(size 0.4064 1.3716)
			(layers "F.Cu" "F.Mask" "F.Paste")
			(net "Net_8981")
		)
		(pad "21" smd rect
			(at 2.925064 -1.625092 270)
			(size 0.4064 1.3716)
			(layers "F.Cu" "F.Mask" "F.Paste")
			(net "PCA9555_0_PEX1_A0")
		)
		(pad "22" smd rect
			(at 2.925064 -2.275078 270)
			(size 0.4064 1.3716)
			(layers "F.Cu" "F.Mask" "F.Paste")
			(net "SMB_PEX1_PCA9555_SCL")
		)
		(pad "23" smd rect
			(at 2.925064 -2.925064 270)
			(size 0.4064 1.3716)
			(layers "F.Cu" "F.Mask" "F.Paste")
			(net "SMB_PEX1_PCA9555_SDA")
		)
		(pad "24" smd rect
			(at 2.925064 -3.674872 270)
			(size 0.6096 1.3716)
			(layers "F.Cu" "F.Mask" "F.Paste")
			(net "P3V3_AUX")
		)
	)
)
